(kicad_pcb
	(version 20260206)
	(generator "pcbnew")
	(generator_version "10.0")
	(general
		(thickness 1.6)
		(legacy_teardrops no)
	)
	(paper "A4")
	(title_block
		(title "m-2 — Lightning_M.2_BRD.brd")
		(comment 1 "Lightning (Wiwynn / Facebook NVMe JBOF) / footprints 32-38 of 157")
	)
	(layers
		(0 "F.Cu" signal "TOP")
		(4 "In1.Cu" signal "L2GND")
		(6 "In2.Cu" signal "L3")
		(8 "In3.Cu" signal "L4GND")
		(10 "In4.Cu" signal "L5GND")
		(12 "In5.Cu" signal "L6")
		(14 "In6.Cu" signal "L7GND")
		(2 "B.Cu" signal "BOTTOM")
		(9 "F.Adhes" user "F.Adhesive")
		(11 "B.Adhes" user "B.Adhesive")
		(13 "F.Paste" user "Package Geometry/Pastemask Top")
		(15 "B.Paste" user "Package Geometry/Pastemask Bottom")
		(5 "F.SilkS" user "Ref Des/Silkscreen Top")
		(7 "B.SilkS" user "Ref Des/Silkscreen Bottom")
		(1 "F.Mask" user "Board Geometry/Soldermask Top")
		(3 "B.Mask" user "Board Geometry/Soldermask Bottom")
		(17 "Dwgs.User" user "User.Drawings")
		(19 "Cmts.User" user "User.Comments")
		(21 "Eco1.User" user "User.Eco1")
		(23 "Eco2.User" user "User.Eco2")
		(25 "Edge.Cuts" user "Board Geometry/Outline")
		(27 "Margin" user)
		(31 "F.CrtYd" user "Package Geometry/Place Bound Top")
		(29 "B.CrtYd" user "Package Geometry/Place Bound Bottom")
		(35 "F.Fab" user "Ref Des/Assembly Top")
		(33 "B.Fab" user "Ref Des/Assembly Bottom")
	)
	(footprint ""
		(layer "F.Cu")
		(at 75.692 -42.037 180)
		(property "Reference" "U5"
			(at 0 0 180)
			(layer "F.SilkS")
			(hide yes)
			(effects
				(font
					(size 1.27 1.27)
				)
			)
		)
		(property "Value" "74LVC1G32DC-1GP"
			(at -2.3368 -8.6868 180)
			(unlocked yes)
			(layer "F.Fab")
			(hide yes)
			(effects
				(font
					(size 1.016 1.016)
					(thickness 0.1524)
				)
			)
		)
		(property "Device Type" "SC70-5H44"
			(at -2.3114 -10.414 180)
			(unlocked yes)
			(layer "F.Fab")
			(hide yes)
			(effects
				(font
					(size 1.016 1.016)
					(thickness 0.1524)
				)
			)
		)
		(duplicate_pad_numbers_are_jumpers no)
		(fp_line
			(start 1.3843 -1.8034)
			(end 1.3843 -1.1176)
			(stroke
				(width 0.3302)
				(type default)
			)
			(layer "F.SilkS")
		)
		(fp_line
			(start 1.27 1.7018)
			(end -1.27 1.7018)
			(stroke
				(width 0.1524)
				(type default)
			)
			(layer "F.SilkS")
		)
		(fp_line
			(start 1.27 -1.7018)
			(end 1.27 1.7018)
			(stroke
				(width 0.1524)
				(type default)
			)
			(layer "F.SilkS")
		)
		(fp_line
			(start 0.6604 -1.8034)
			(end 1.3843 -1.8034)
			(stroke
				(width 0.3302)
				(type default)
			)
			(layer "F.SilkS")
		)
		(fp_line
			(start -1.27 1.7018)
			(end -1.27 -1.7018)
			(stroke
				(width 0.1524)
				(type default)
			)
			(layer "F.SilkS")
		)
		(fp_line
			(start -1.27 -1.7018)
			(end 1.27 -1.7018)
			(stroke
				(width 0.1524)
				(type default)
			)
			(layer "F.SilkS")
		)
		(fp_rect
			(start -1.524 1.9558)
			(end 1.524 -1.9558)
			(stroke
				(width 0)
				(type default)
			)
			(fill no)
			(layer "F.CrtYd")
		)
		(fp_poly
			(pts
				(xy -1.524 -1.9558) (xy 1.524 -1.9558) (xy 1.524 1.9558) (xy -1.524 1.9558)
			)
			(stroke
				(width 0)
				(type default)
			)
			(fill no)
			(layer "F.Fab")
		)
		(pad "1" smd rect
			(at 0.65024 -0.8255 180)
			(size 0.4064 1.2192)
			(layers "F.Cu" "F.Mask" "F.Paste")
			(net "Z50_SSD_A_PRSNT#")
		)
		(pad "2" smd rect
			(at 0 -0.8255 180)
			(size 0.4064 1.2192)
			(layers "F.Cu" "F.Mask" "F.Paste")
			(net "Z50_SSD_B_PRSNT#")
		)
		(pad "3" smd rect
			(at -0.65024 -0.8255 180)
			(size 0.4064 1.2192)
			(layers "F.Cu" "F.Mask" "F.Paste")
			(net "GND")
		)
		(pad "4" smd rect
			(at -0.65024 0.8255 180)
			(size 0.4064 1.2192)
			(layers "F.Cu" "F.Mask" "F.Paste")
			(net "Z50_SSD_M2_PRSNT#")
		)
		(pad "5" smd rect
			(at 0.65024 0.8255 180)
			(size 0.4064 1.2192)
			(layers "F.Cu" "F.Mask" "F.Paste")
			(net "P3V3_DPB")
		)
	)
	(footprint ""
		(layer "F.Cu")
		(at 14.732 -82.598006 -90)
		(property "Reference" "PC20"
			(at 0 0 270)
			(layer "F.SilkS")
			(hide yes)
			(effects
				(font
					(size 1.27 1.27)
				)
			)
		)
		(property "Value" "SCD01U25V2KX-3GP"
			(at 1.1811 -2.7051 270)
			(unlocked yes)
			(layer "F.Fab")
			(hide yes)
			(effects
				(font
					(size 1.016 1.016)
					(thickness 0.1524)
				)
			)
		)
		(property "Device Type" "C402H22"
			(at 1.1811 -4.2291 270)
			(unlocked yes)
			(layer "F.Fab")
			(hide yes)
			(effects
				(font
					(size 1.016 1.016)
					(thickness 0.1524)
				)
			)
		)
		(duplicate_pad_numbers_are_jumpers no)
		(fp_rect
			(start -0.4318 0.9525)
			(end 0.4318 -0.9525)
			(stroke
				(width 0)
				(type default)
			)
			(fill no)
			(layer "F.CrtYd")
		)
		(fp_rect
			(start -0.4318 0.9525)
			(end 0.4318 -0.9525)
			(stroke
				(width 0)
				(type default)
			)
			(fill no)
			(layer "F.Fab")
		)
		(pad "1" smd custom
			(at 0 -0.4445 270)
			(size 0.1524 0.1524)
			(layers "F.Cu" "F.Mask" "F.Paste")
			(net "P1V8_PWR_EN_R")
			(options
				(clearance outline)
				(anchor circle)
			)
			(primitives
				(gr_poly
					(pts
						(arc
							(start 0.3048 -0.2032)
							(mid 0.275042 -0.275042)
							(end 0.2032 -0.3048)
						)
						(arc
							(start -0.2032 -0.3048)
							(mid -0.275042 -0.275042)
							(end -0.3048 -0.2032)
						)
						(arc
							(start -0.3048 0.2032)
							(mid -0.275042 0.275042)
							(end -0.2032 0.3048)
						)
						(arc
							(start 0.2032 0.3048)
							(mid 0.275042 0.275042)
							(end 0.3048 0.2032)
						)
					)
					(width 0)
					(fill yes)
				)
			)
		)
		(pad "2" smd custom
			(at 0 0.4445 270)
			(size 0.1524 0.1524)
			(layers "F.Cu" "F.Mask" "F.Paste")
			(net "GND")
			(options
				(clearance outline)
				(anchor circle)
			)
			(primitives
				(gr_poly
					(pts
						(arc
							(start 0.3048 -0.2032)
							(mid 0.275042 -0.275042)
							(end 0.2032 -0.3048)
						)
						(arc
							(start -0.2032 -0.3048)
							(mid -0.275042 -0.275042)
							(end -0.3048 -0.2032)
						)
						(arc
							(start -0.3048 0.2032)
							(mid -0.275042 0.275042)
							(end -0.2032 0.3048)
						)
						(arc
							(start 0.2032 0.3048)
							(mid 0.275042 0.275042)
							(end 0.3048 0.2032)
						)
					)
					(width 0)
					(fill yes)
				)
			)
		)
	)
	(footprint ""
		(layer "F.Cu")
		(at 75.184 -35.941)
		(property "Reference" "R4"
			(at 0 0 0)
			(layer "F.SilkS")
			(hide yes)
			(effects
				(font
					(size 1.27 1.27)
				)
			)
		)
		(property "Value" "0R2J-2-GP"
			(at 0.064008 -3.993896 0)
			(unlocked yes)
			(layer "F.Fab")
			(hide yes)
			(effects
				(font
					(size 1.016 1.016)
					(thickness 0.1524)
				)
			)
		)
		(property "Device Type" "R402H16"
			(at 0.064008 -5.517896 0)
			(unlocked yes)
			(layer "F.Fab")
			(hide yes)
			(effects
				(font
					(size 1.016 1.016)
					(thickness 0.1524)
				)
			)
		)
		(duplicate_pad_numbers_are_jumpers no)
		(fp_line
			(start -0.508 -0.9398)
			(end -0.508 0.9398)
			(stroke
				(width 0.1524)
				(type default)
			)
			(layer "F.SilkS")
		)
		(fp_line
			(start 0.508 -0.9398)
			(end -0.508 -0.9398)
			(stroke
				(width 0.1524)
				(type default)
			)
			(layer "F.SilkS")
		)
		(fp_rect
			(start -0.508 0.9398)
			(end 0.508 -0.9398)
			(stroke
				(width 0)
				(type default)
			)
			(fill no)
			(layer "F.CrtYd")
		)
		(fp_rect
			(start -0.508 0.9398)
			(end 0.508 -0.9398)
			(stroke
				(width 0)
				(type default)
			)
			(fill no)
			(layer "F.Fab")
		)
		(pad "1" smd custom
			(at 0 -0.4445)
			(size 0.1397 0.1397)
			(layers "F.Cu" "F.Mask" "F.Paste")
			(net "Z50_SSD_B_PRESENT_R#")
			(options
				(clearance outline)
				(anchor circle)
			)
			(primitives
				(gr_poly
					(pts
						(arc
							(start -0.1778 -0.2794)
							(mid -0.249642 -0.249642)
							(end -0.2794 -0.1778)
						)
						(arc
							(start -0.2794 0.1778)
							(mid -0.249642 0.249642)
							(end -0.1778 0.2794)
						)
						(arc
							(start 0.1778 0.2794)
							(mid 0.249642 0.249642)
							(end 0.2794 0.1778)
						)
						(arc
							(start 0.2794 -0.1778)
							(mid 0.249642 -0.249642)
							(end 0.1778 -0.2794)
						)
					)
					(width 0)
					(fill yes)
				)
			)
		)
		(pad "2" smd custom
			(at 0 0.4445)
			(size 0.1397 0.1397)
			(layers "F.Cu" "F.Mask" "F.Paste")
			(net "Z50_SSD_B_PRSNT#")
			(options
				(clearance outline)
				(anchor circle)
			)
			(primitives
				(gr_poly
					(pts
						(arc
							(start -0.1778 -0.2794)
							(mid -0.249642 -0.249642)
							(end -0.2794 -0.1778)
						)
						(arc
							(start -0.2794 0.1778)
							(mid -0.249642 0.249642)
							(end -0.1778 0.2794)
						)
						(arc
							(start 0.1778 0.2794)
							(mid 0.249642 0.249642)
							(end 0.2794 0.1778)
						)
						(arc
							(start 0.2794 -0.1778)
							(mid 0.249642 -0.249642)
							(end 0.1778 -0.2794)
						)
					)
					(width 0)
					(fill yes)
				)
			)
		)
	)
	(footprint ""
		(layer "F.Cu")
		(at 44.782994 -76.2 180)
		(property "Reference" "PR32"
			(at 0 0 180)
			(layer "F.SilkS")
			(hide yes)
			(effects
				(font
					(size 1.27 1.27)
				)
			)
		)
		(property "Value" "866KR2F-GP"
			(at 0.064008 -3.993896 180)
			(unlocked yes)
			(layer "F.Fab")
			(hide yes)
			(effects
				(font
					(size 1.016 1.016)
					(thickness 0.1524)
				)
			)
		)
		(property "Device Type" "R402H16"
			(at 0.064008 -5.517896 180)
			(unlocked yes)
			(layer "F.Fab")
			(hide yes)
			(effects
				(font
					(size 1.016 1.016)
					(thickness 0.1524)
				)
			)
		)
		(duplicate_pad_numbers_are_jumpers no)
		(fp_line
			(start 0.508 -0.9398)
			(end -0.508 -0.9398)
			(stroke
				(width 0.1524)
				(type default)
			)
			(layer "F.SilkS")
		)
		(fp_line
			(start -0.508 -0.9398)
			(end -0.508 0.9398)
			(stroke
				(width 0.1524)
				(type default)
			)
			(layer "F.SilkS")
		)
		(fp_rect
			(start -0.508 0.9398)
			(end 0.508 -0.9398)
			(stroke
				(width 0)
				(type default)
			)
			(fill no)
			(layer "F.CrtYd")
		)
		(fp_rect
			(start -0.508 0.9398)
			(end 0.508 -0.9398)
			(stroke
				(width 0)
				(type default)
			)
			(fill no)
			(layer "F.Fab")
		)
		(pad "1" smd custom
			(at 0 -0.4445 180)
			(size 0.1397 0.1397)
			(layers "F.Cu" "F.Mask" "F.Paste")
			(net "P3V3_DEV_VREG")
			(options
				(clearance outline)
				(anchor circle)
			)
			(primitives
				(gr_poly
					(pts
						(arc
							(start -0.1778 -0.2794)
							(mid -0.249642 -0.249642)
							(end -0.2794 -0.1778)
						)
						(arc
							(start -0.2794 0.1778)
							(mid -0.249642 0.249642)
							(end -0.1778 0.2794)
						)
						(arc
							(start 0.1778 0.2794)
							(mid 0.249642 0.249642)
							(end 0.2794 0.1778)
						)
						(arc
							(start 0.2794 -0.1778)
							(mid 0.249642 -0.249642)
							(end 0.1778 -0.2794)
						)
					)
					(width 0)
					(fill yes)
				)
			)
		)
		(pad "2" smd custom
			(at 0 0.4445 180)
			(size 0.1397 0.1397)
			(layers "F.Cu" "F.Mask" "F.Paste")
			(net "P3V3_DEV_RF")
			(options
				(clearance outline)
				(anchor circle)
			)
			(primitives
				(gr_poly
					(pts
						(arc
							(start -0.1778 -0.2794)
							(mid -0.249642 -0.249642)
							(end -0.2794 -0.1778)
						)
						(arc
							(start -0.2794 0.1778)
							(mid -0.249642 0.249642)
							(end -0.1778 0.2794)
						)
						(arc
							(start 0.1778 0.2794)
							(mid 0.249642 0.249642)
							(end 0.2794 0.1778)
						)
						(arc
							(start 0.2794 -0.1778)
							(mid 0.249642 -0.249642)
							(end 0.1778 -0.2794)
						)
					)
					(width 0)
					(fill yes)
				)
			)
		)
	)
	(footprint ""
		(layer "F.Cu")
		(at 59.817 -58.547 -90)
		(property "Reference" "C19"
			(at 0 0 270)
			(layer "F.SilkS")
			(hide yes)
			(effects
				(font
					(size 1.27 1.27)
				)
			)
		)
		(property "Value" "SC1U6D3V2KX-9-GP"
			(at 1.1811 -2.7051 270)
			(unlocked yes)
			(layer "F.Fab")
			(hide yes)
			(effects
				(font
					(size 1.016 1.016)
					(thickness 0.1524)
				)
			)
		)
		(property "Device Type" "C402H22"
			(at 1.1811 -4.2291 270)
			(unlocked yes)
			(layer "F.Fab")
			(hide yes)
			(effects
				(font
					(size 1.016 1.016)
					(thickness 0.1524)
				)
			)
		)
		(duplicate_pad_numbers_are_jumpers no)
		(fp_rect
			(start -0.4318 0.9525)
			(end 0.4318 -0.9525)
			(stroke
				(width 0)
				(type default)
			)
			(fill no)
			(layer "F.CrtYd")
		)
		(fp_rect
			(start -0.4318 0.9525)
			(end 0.4318 -0.9525)
			(stroke
				(width 0)
				(type default)
			)
			(fill no)
			(layer "F.Fab")
		)
		(pad "1" smd custom
			(at 0 -0.4445 270)
			(size 0.1524 0.1524)
			(layers "F.Cu" "F.Mask" "F.Paste")
			(net "P3V3_PWR")
			(options
				(clearance outline)
				(anchor circle)
			)
			(primitives
				(gr_poly
					(pts
						(arc
							(start 0.3048 -0.2032)
							(mid 0.275042 -0.275042)
							(end 0.2032 -0.3048)
						)
						(arc
							(start -0.2032 -0.3048)
							(mid -0.275042 -0.275042)
							(end -0.3048 -0.2032)
						)
						(arc
							(start -0.3048 0.2032)
							(mid -0.275042 0.275042)
							(end -0.2032 0.3048)
						)
						(arc
							(start 0.2032 0.3048)
							(mid 0.275042 0.275042)
							(end 0.3048 0.2032)
						)
					)
					(width 0)
					(fill yes)
				)
			)
		)
		(pad "2" smd custom
			(at 0 0.4445 270)
			(size 0.1524 0.1524)
			(layers "F.Cu" "F.Mask" "F.Paste")
			(net "GND")
			(options
				(clearance outline)
				(anchor circle)
			)
			(primitives
				(gr_poly
					(pts
						(arc
							(start 0.3048 -0.2032)
							(mid 0.275042 -0.275042)
							(end 0.2032 -0.3048)
						)
						(arc
							(start -0.2032 -0.3048)
							(mid -0.275042 -0.275042)
							(end -0.3048 -0.2032)
						)
						(arc
							(start -0.3048 0.2032)
							(mid -0.275042 0.275042)
							(end -0.2032 0.3048)
						)
						(arc
							(start 0.2032 0.3048)
							(mid 0.275042 0.275042)
							(end 0.3048 0.2032)
						)
					)
					(width 0)
					(fill yes)
				)
			)
		)
	)
	(footprint ""
		(layer "F.Cu")
		(at 63.246 -83.185 180)
		(property "Reference" "PC45"
			(at 0 0 180)
			(layer "F.SilkS")
			(hide yes)
			(effects
				(font
					(size 1.27 1.27)
				)
			)
		)
		(property "Value" "ST150U6D3VDM-28-GP"
			(at 0 -9.6012 180)
			(unlocked yes)
			(layer "F.Fab")
			(hide yes)
			(effects
				(font
					(size 1.016 1.016)
					(thickness 0.1524)
				)
			)
		)
		(property "Device Type" "CT7343H83"
			(at 0 -11.1252 180)
			(unlocked yes)
			(layer "F.Fab")
			(hide yes)
			(effects
				(font
					(size 1.016 1.016)
					(thickness 0.1524)
				)
			)
		)
		(duplicate_pad_numbers_are_jumpers no)
		(fp_line
			(start 2.286 4.8768)
			(end -2.286 4.8768)
			(stroke
				(width 0.1524)
				(type default)
			)
			(layer "F.SilkS")
		)
		(fp_line
			(start 2.286 2.032)
			(end 2.286 4.8768)
			(stroke
				(width 0.1524)
				(type default)
			)
			(layer "F.SilkS")
		)
		(fp_line
			(start 2.286 -2.032)
			(end 2.286 -4.8768)
			(stroke
				(width 0.1524)
				(type default)
			)
			(layer "F.SilkS")
		)
		(fp_line
			(start 2.286 -4.8768)
			(end -2.286 -4.8768)
			(stroke
				(width 0.1524)
				(type default)
			)
			(layer "F.SilkS")
		)
		(fp_line
			(start 2.1082 -4.699)
			(end -2.1082 -4.699)
			(stroke
				(width 0.508)
				(type default)
			)
			(layer "F.SilkS")
		)
		(fp_line
			(start -2.286 4.8768)
			(end -2.286 2.032)
			(stroke
				(width 0.1524)
				(type default)
			)
			(layer "F.SilkS")
		)
		(fp_line
			(start -2.286 -4.8768)
			(end -2.286 -2.032)
			(stroke
				(width 0.1524)
				(type default)
			)
			(layer "F.SilkS")
		)
		(fp_rect
			(start -2.1463 3.6449)
			(end 2.1463 -3.6449)
			(stroke
				(width 0)
				(type default)
			)
			(fill no)
			(layer "F.CrtYd")
		)
		(fp_poly
			(pts
				(xy -2.54 4.953) (xy -2.54 4.2926) (xy -3.81 4.2926) (xy -3.81 -4.2926) (xy -2.54 -4.2926) (xy -2.54 -4.953)
				(xy 2.54 -4.953) (xy 2.54 -4.2926) (xy 3.81 -4.2926) (xy 3.81 -1.6256) (xy 2.1463 -1.6256) (xy 2.1463 -3.6449)
				(xy -2.1463 -3.6449) (xy -2.1463 3.6449) (xy 2.1463 3.6449) (xy 2.1463 -1.6129) (xy 3.81 -1.6129)
				(xy 3.81 4.2926) (xy 2.54 4.2926) (xy 2.54 4.953)
			)
			(stroke
				(width 0)
				(type default)
			)
			(fill no)
			(layer "F.CrtYd")
		)
		(fp_rect
			(start 2.54 4.2926)
			(end 3.81 -4.2926)
			(stroke
				(width 0)
				(type default)
			)
			(fill no)
			(layer "F.Fab")
		)
		(fp_rect
			(start -2.54 4.953)
			(end 2.54 -4.953)
			(stroke
				(width 0)
				(type default)
			)
			(fill no)
			(layer "F.Fab")
		)
		(fp_rect
			(start -3.81 4.2926)
			(end -2.54 -4.2926)
			(stroke
				(width 0)
				(type default)
			)
			(fill no)
			(layer "F.Fab")
		)
		(pad "1" smd rect
			(at 0 -3.1496 180)
			(size 2.413 2.286)
			(layers "F.Cu" "F.Mask" "F.Paste")
			(net "P3V3_PWR")
		)
		(pad "2" smd rect
			(at 0 3.1496 180)
			(size 2.413 2.286)
			(layers "F.Cu" "F.Mask" "F.Paste")
			(net "GND")
		)
		(zone
			(layer "F.Cu")
			(hatch none 0.5)
			(connect_pads
				(clearance 0)
			)
			(min_thickness 0.25)
			(keepout
				(tracks allowed)
				(vias not_allowed)
				(pads allowed)
				(copperpour not_allowed)
				(footprints allowed)
			)
			(placement
				(enabled no)
				(sheetname "")
			)
			(fill
				(thermal_gap 0.5)
				(thermal_bridge_width 0.5)
				(island_removal_mode 0)
			)
			(polygon
				(pts
					(xy 61.7347 -81.4959) (xy 61.7347 -78.5876) (xy 64.7573 -78.5876) (xy 64.7573 -81.4832) (xy 64.7573 -81.8134)
					(xy 61.7347 -81.8134)
				)
			)
		)
		(zone
			(layer "F.Cu")
			(hatch none 0.5)
			(connect_pads
				(clearance 0)
			)
			(min_thickness 0.25)
			(keepout
				(tracks allowed)
				(vias not_allowed)
				(pads allowed)
				(copperpour not_allowed)
				(footprints allowed)
			)
			(placement
				(enabled no)
				(sheetname "")
			)
			(fill
				(thermal_gap 0.5)
				(thermal_bridge_width 0.5)
				(island_removal_mode 0)
			)
			(polygon
				(pts
					(xy 64.7573 -87.7824) (xy 61.7347 -87.7824) (xy 61.7347 -84.8868) (xy 61.7347 -84.5566) (xy 64.7573 -84.5566)
					(xy 64.7573 -84.8868)
				)
			)
		)
	)
	(footprint ""
		(layer "F.Cu")
		(at 59.817 -32.004 -90)
		(property "Reference" "C37"
			(at 0 0 270)
			(layer "F.SilkS")
			(hide yes)
			(effects
				(font
					(size 1.27 1.27)
				)
			)
		)
		(property "Value" "SC1U6D3V2KX-9-GP"
			(at 1.1811 -2.7051 270)
			(unlocked yes)
			(layer "F.Fab")
			(hide yes)
			(effects
				(font
					(size 1.016 1.016)
					(thickness 0.1524)
				)
			)
		)
		(property "Device Type" "C402H22"
			(at 1.1811 -4.2291 270)
			(unlocked yes)
			(layer "F.Fab")
			(hide yes)
			(effects
				(font
					(size 1.016 1.016)
					(thickness 0.1524)
				)
			)
		)
		(duplicate_pad_numbers_are_jumpers no)
		(fp_rect
			(start -0.4318 0.9525)
			(end 0.4318 -0.9525)
			(stroke
				(width 0)
				(type default)
			)
			(fill no)
			(layer "F.CrtYd")
		)
		(fp_rect
			(start -0.4318 0.9525)
			(end 0.4318 -0.9525)
			(stroke
				(width 0)
				(type default)
			)
			(fill no)
			(layer "F.Fab")
		)
		(pad "1" smd custom
			(at 0 -0.4445 270)
			(size 0.1524 0.1524)
			(layers "F.Cu" "F.Mask" "F.Paste")
			(net "P3V3_PWR")
			(options
				(clearance outline)
				(anchor circle)
			)
			(primitives
				(gr_poly
					(pts
						(arc
							(start 0.3048 -0.2032)
							(mid 0.275042 -0.275042)
							(end 0.2032 -0.3048)
						)
						(arc
							(start -0.2032 -0.3048)
							(mid -0.275042 -0.275042)
							(end -0.3048 -0.2032)
						)
						(arc
							(start -0.3048 0.2032)
							(mid -0.275042 0.275042)
							(end -0.2032 0.3048)
						)
						(arc
							(start 0.2032 0.3048)
							(mid 0.275042 0.275042)
							(end 0.3048 0.2032)
						)
					)
					(width 0)
					(fill yes)
				)
			)
		)
		(pad "2" smd custom
			(at 0 0.4445 270)
			(size 0.1524 0.1524)
			(layers "F.Cu" "F.Mask" "F.Paste")
			(net "GND")
			(options
				(clearance outline)
				(anchor circle)
			)
			(primitives
				(gr_poly
					(pts
						(arc
							(start 0.3048 -0.2032)
							(mid 0.275042 -0.275042)
							(end 0.2032 -0.3048)
						)
						(arc
							(start -0.2032 -0.3048)
							(mid -0.275042 -0.275042)
							(end -0.3048 -0.2032)
						)
						(arc
							(start -0.3048 0.2032)
							(mid -0.275042 0.275042)
							(end -0.2032 0.3048)
						)
						(arc
							(start 0.2032 0.3048)
							(mid 0.275042 0.275042)
							(end 0.3048 0.2032)
						)
					)
					(width 0)
					(fill yes)
				)
			)
		)
	)
)
